(kicad_pcb
	(version 20260206)
	(generator "pcbnew")
	(generator_version "10.0")
	(general
		(thickness 1.21888)
		(legacy_teardrops no)
	)
	(paper "A4")
	(title_block
		(title "timecard-proto-v0 — Timingcard_PCB.PcbDoc")
		(comment 1 "Time Appliance Project (Time Card) / footprints 161-167 of 167")
	)
	(layers
		(0 "F.Cu" signal "TOP")
		(4 "In1.Cu" signal "SGND")
		(6 "In2.Cu" signal "IN1")
		(8 "In3.Cu" signal "IN2")
		(10 "In4.Cu" signal "SGND1")
		(2 "B.Cu" signal "BOTTOM")
		(9 "F.Adhes" user "F.Adhesive")
		(11 "B.Adhes" user "B.Adhesive")
		(13 "F.Paste" user "Top Paste")
		(15 "B.Paste" user "Bottom Paste")
		(5 "F.SilkS" user "Top Overlay")
		(7 "B.SilkS" user "Bottom Overlay")
		(1 "F.Mask" user "Top Solder")
		(3 "B.Mask" user "Bottom Solder")
		(17 "Dwgs.User" user "User.Drawings")
		(19 "Cmts.User" user "User.Comments")
		(21 "Eco1.User" user "User.Eco1")
		(23 "Eco2.User" user "User.Eco2")
		(25 "Edge.Cuts" user)
		(27 "Margin" user)
		(31 "F.CrtYd" user "Top Courtyard")
		(29 "B.CrtYd" user "Bottom Courtyard")
		(35 "F.Fab" user "Top Component Center")
		(33 "B.Fab" user "Bottom Component Center")
	)
	(footprint "Vault:CAPC1608X87X45ML20T05"
		(layer "B.Cu")
		(at 127.388595 83.9786 90)
		(property "Reference" "C90"
			(at -3.7 -0.493345 270)
			(unlocked yes)
			(layer "B.SilkS")
			(effects
				(font
					(size 0.762 0.762)
					(thickness 0.254)
				)
				(justify left bottom mirror)
			)
		)
		(property "Value" "0.1uF"
			(at -3.47599 0.2921 0)
			(unlocked yes)
			(layer "B.SilkS")
			(hide yes)
			(effects
				(font
					(size 1.524 1.524)
					(thickness 0.254)
				)
				(justify left bottom mirror)
			)
		)
		(sheetname "GPS_IMU_SENSORS")
		(sheetfile "GPS_IMU_SENSORS.kicad_sch")
		(duplicate_pad_numbers_are_jumpers no)
		(pad "1" smd rect
			(at -0.7 0)
			(size 1.1 1.05)
			(layers "B.Cu" "B.Mask" "B.Paste")
			(net "GND")
		)
		(pad "2" smd rect
			(at 0.7 0)
			(size 1.1 1.05)
			(layers "B.Cu" "B.Mask" "B.Paste")
			(net "+5.0V")
		)
	)
	(footprint "Capacitors:CAPC1005X06N"
		(layer "B.Cu")
		(at 135.192595 151.7886 90)
		(property "Reference" "C53"
			(at 2.41349 0.046545 270)
			(unlocked yes)
			(layer "B.SilkS")
			(effects
				(font
					(size 0.762 0.762)
					(thickness 0.254)
				)
				(justify left bottom mirror)
			)
		)
		(property "Value" "CAP_0402_0.1UF_50V"
			(at -3.47599 0.2921 0)
			(unlocked yes)
			(layer "B.SilkS")
			(hide yes)
			(effects
				(font
					(size 1.524 1.524)
					(thickness 0.254)
				)
				(justify left bottom mirror)
			)
		)
		(sheetname "PCIe_JTAG")
		(sheetfile "PCIe_JTAG.kicad_sch")
		(duplicate_pad_numbers_are_jumpers no)
		(pad "1" smd rect
			(at -0.43 0)
			(size 0.64 0.68)
			(layers "B.Cu" "B.Mask" "B.Paste")
			(net "NetC53_1")
		)
		(pad "2" smd rect
			(at 0.43 0)
			(size 0.64 0.68)
			(layers "B.Cu" "B.Mask" "B.Paste")
			(net "PCIE_TX3_N")
		)
	)
	(footprint "Capacitors:CAPC1005X06N"
		(layer "B.Cu")
		(at 121.197195 151.7886 90)
		(property "Reference" "C46"
			(at 2.41349 -0.563055 270)
			(unlocked yes)
			(layer "B.SilkS")
			(effects
				(font
					(size 0.762 0.762)
					(thickness 0.254)
				)
				(justify left bottom mirror)
			)
		)
		(property "Value" "CAP_0402_0.1UF_50V"
			(at -3.47599 0.2921 0)
			(unlocked yes)
			(layer "B.SilkS")
			(hide yes)
			(effects
				(font
					(size 1.524 1.524)
					(thickness 0.254)
				)
				(justify left bottom mirror)
			)
		)
		(sheetname "PCIe_JTAG")
		(sheetfile "PCIe_JTAG.kicad_sch")
		(duplicate_pad_numbers_are_jumpers no)
		(pad "1" smd rect
			(at -0.43 0)
			(size 0.64 0.68)
			(layers "B.Cu" "B.Mask" "B.Paste")
			(net "NetC46_1")
		)
		(pad "2" smd rect
			(at 0.43 0)
			(size 0.64 0.68)
			(layers "B.Cu" "B.Mask" "B.Paste")
			(net "PCIE_TX0_P")
		)
	)
	(footprint "Capacitors:CAPC1005X06N"
		(layer "B.Cu")
		(at 131.001595 151.7886 90)
		(property "Reference" "C51"
			(at 2.41349 0.148145 270)
			(unlocked yes)
			(layer "B.SilkS")
			(effects
				(font
					(size 0.762 0.762)
					(thickness 0.254)
				)
				(justify left bottom mirror)
			)
		)
		(property "Value" "CAP_0402_0.1UF_50V"
			(at -3.47599 0.2921 0)
			(unlocked yes)
			(layer "B.SilkS")
			(hide yes)
			(effects
				(font
					(size 1.524 1.524)
					(thickness 0.254)
				)
				(justify left bottom mirror)
			)
		)
		(sheetname "PCIe_JTAG")
		(sheetfile "PCIe_JTAG.kicad_sch")
		(duplicate_pad_numbers_are_jumpers no)
		(pad "1" smd rect
			(at -0.43 0)
			(size 0.64 0.68)
			(layers "B.Cu" "B.Mask" "B.Paste")
			(net "NetC51_1")
		)
		(pad "2" smd rect
			(at 0.43 0)
			(size 0.64 0.68)
			(layers "B.Cu" "B.Mask" "B.Paste")
			(net "PCIE_TX2_N")
		)
	)
	(footprint "Capacitors:CAPC1005X06N"
		(layer "B.Cu")
		(at 122.289395 151.7886 90)
		(property "Reference" "C47"
			(at 2.41349 0.097345 270)
			(unlocked yes)
			(layer "B.SilkS")
			(effects
				(font
					(size 0.762 0.762)
					(thickness 0.254)
				)
				(justify left bottom mirror)
			)
		)
		(property "Value" "CAP_0402_0.1UF_50V"
			(at -3.47599 0.2921 0)
			(unlocked yes)
			(layer "B.SilkS")
			(hide yes)
			(effects
				(font
					(size 1.524 1.524)
					(thickness 0.254)
				)
				(justify left bottom mirror)
			)
		)
		(sheetname "PCIe_JTAG")
		(sheetfile "PCIe_JTAG.kicad_sch")
		(duplicate_pad_numbers_are_jumpers no)
		(pad "1" smd rect
			(at -0.43 0)
			(size 0.64 0.68)
			(layers "B.Cu" "B.Mask" "B.Paste")
			(net "NetC47_1")
		)
		(pad "2" smd rect
			(at 0.43 0)
			(size 0.64 0.68)
			(layers "B.Cu" "B.Mask" "B.Paste")
			(net "PCIE_TX0_N")
		)
	)
	(footprint "Capacitors:CAPC1005X06N"
		(layer "B.Cu")
		(at 118.174595 151.7886 90)
		(property "Reference" "C44"
			(at 2.885 -1.204345 270)
			(unlocked yes)
			(layer "B.SilkS")
			(effects
				(font
					(size 0.762 0.762)
					(thickness 0.254)
				)
				(justify left bottom mirror)
			)
		)
		(property "Value" "CAP_0402_0.1UF_50V"
			(at -3.47599 0.2921 0)
			(unlocked yes)
			(layer "B.SilkS")
			(hide yes)
			(effects
				(font
					(size 1.524 1.524)
					(thickness 0.254)
				)
				(justify left bottom mirror)
			)
		)
		(sheetname "PCIe_JTAG")
		(sheetfile "PCIe_JTAG.kicad_sch")
		(duplicate_pad_numbers_are_jumpers no)
		(pad "1" smd rect
			(at -0.43 0)
			(size 0.64 0.68)
			(layers "B.Cu" "B.Mask" "B.Paste")
			(net "NetC44_1")
		)
		(pad "2" smd rect
			(at 0.43 0)
			(size 0.64 0.68)
			(layers "B.Cu" "B.Mask" "B.Paste")
			(net "PCIE_CLK_P")
		)
	)
	(footprint "Capacitors:CAPC1005X06N"
		(layer "B.Cu")
		(at 119.190595 151.7886 90)
		(property "Reference" "C45"
			(at 2.835 -0.445345 270)
			(unlocked yes)
			(layer "B.SilkS")
			(effects
				(font
					(size 0.762 0.762)
					(thickness 0.254)
				)
				(justify left bottom mirror)
			)
		)
		(property "Value" "CAP_0402_0.1UF_50V"
			(at -3.47599 0.2921 0)
			(unlocked yes)
			(layer "B.SilkS")
			(hide yes)
			(effects
				(font
					(size 1.524 1.524)
					(thickness 0.254)
				)
				(justify left bottom mirror)
			)
		)
		(sheetname "PCIe_JTAG")
		(sheetfile "PCIe_JTAG.kicad_sch")
		(duplicate_pad_numbers_are_jumpers no)
		(pad "1" smd rect
			(at -0.43 0)
			(size 0.64 0.68)
			(layers "B.Cu" "B.Mask" "B.Paste")
			(net "NetC45_1")
		)
		(pad "2" smd rect
			(at 0.43 0)
			(size 0.64 0.68)
			(layers "B.Cu" "B.Mask" "B.Paste")
			(net "PCIE_CLK_N")
		)
	)
)
